# S9S_MB_2U (Grand Teton) — schematic netlist excerpt (pin names and nets, part order shuffled) for the footprints in the layout excerpt that follows; sources: Cadence DE-HDL packaged netlist, KiCad conversion of 03242023_DA0F0TMBIJ0_F0T_Motherboard_J_brd_V01_OCP.brd

PR260  Q_RES  0 5% EMPTY  pkg 0402LF  page 292 : A = P12V_AUX ; B = PVCCINFAON_CPU1_CSPIN
PC1199_P1_3  Q_CAP  22UF 16V 20% X6S  pkg C0805  page 290 : A = SW_P12V_PVCCFA_EHV_FIVRA_CPU1_R ; B = GND
C14  Q_CAP  2.2UF 6.3V 20% X6S  pkg C0402  page 86 : A = P3V3_AUX ; B = GND

(kicad_pcb
	(version 20260206)
	(generator "pcbnew")
	(generator_version "10.0")
	(general
		(thickness 1.6)
		(legacy_teardrops no)
	)
	(paper "A4")
	(title_block
		(title "03242023_DA0F0TMBIJ0_F0T_Motherboard_J_brd_V01_OCP.brd")
		(comment 1 "Grand Teton / footprints 4391-4393 of 6105")
	)
	(layers
		(0 "F.Cu" signal "TOP")
		(4 "In1.Cu" signal "GND")
		(6 "In2.Cu" signal "IN1")
		(8 "In3.Cu" signal "GND1")
		(10 "In4.Cu" signal "IN2")
		(12 "In5.Cu" signal "GND2")
		(14 "In6.Cu" signal "IN3")
		(16 "In7.Cu" signal "GND3")
		(18 "In8.Cu" signal "VCC")
		(20 "In9.Cu" signal "VCC1")
		(22 "In10.Cu" signal "GND4")
		(24 "In11.Cu" signal "IN4")
		(26 "In12.Cu" signal "GND5")
		(28 "In13.Cu" signal "IN5")
		(30 "In14.Cu" signal "GND6")
		(32 "In15.Cu" signal "IN6")
		(34 "In16.Cu" signal "GND7")
		(2 "B.Cu" signal "BOTTOM")
		(9 "F.Adhes" user "F.Adhesive")
		(11 "B.Adhes" user "B.Adhesive")
		(13 "F.Paste" user "Package Geometry/Pastemask Top")
		(15 "B.Paste" user "Package Geometry/Pastemask Bottom")
		(5 "F.SilkS" user "Ref Des/Silkscreen Top")
		(7 "B.SilkS" user "Ref Des/Silkscreen Bottom")
		(1 "F.Mask" user "Board Geometry/Soldermask Top")
		(3 "B.Mask" user "Board Geometry/Soldermask Bottom")
		(17 "Dwgs.User" user "User.Drawings")
		(19 "Cmts.User" user "User.Comments")
		(21 "Eco1.User" user "User.Eco1")
		(23 "Eco2.User" user "User.Eco2")
		(25 "Edge.Cuts" user "Board Geometry/Outline")
		(27 "Margin" user)
		(31 "F.CrtYd" user "Package Geometry/Place Bound Top")
		(29 "B.CrtYd" user "Package Geometry/Place Bound Bottom")
		(35 "F.Fab" user "Ref Des/Assembly Top")
		(33 "B.Fab" user "Ref Des/Assembly Bottom")
	)
	(footprint ""
		(layer "B.Cu")
		(at 271.180814 -319.263776 180)
		(property "Reference" "C14"
			(at 0 0 0)
			(layer "B.SilkS")
			(hide yes)
			(effects
				(font
					(size 1.27 1.27)
				)
				(justify mirror)
			)
		)
		(property "Value" ""
			(at 0 0 0)
			(layer "B.Fab")
			(effects
				(font
					(size 1.27 1.27)
				)
				(justify mirror)
			)
		)
		(duplicate_pad_numbers_are_jumpers no)
		(fp_line
			(start 0.7874 0.4064)
			(end 0.7874 -0.4064)
			(stroke
				(width 0.1524)
				(type default)
			)
			(layer "B.SilkS")
		)
		(fp_line
			(start 0.7874 -0.4064)
			(end -0.7874 -0.4064)
			(stroke
				(width 0.1524)
				(type default)
			)
			(layer "B.SilkS")
		)
		(fp_line
			(start -0.7874 0.4064)
			(end 0.7874 0.4064)
			(stroke
				(width 0.1524)
				(type default)
			)
			(layer "B.SilkS")
		)
		(fp_line
			(start -0.7874 -0.4064)
			(end -0.7874 0.4064)
			(stroke
				(width 0.1524)
				(type default)
			)
			(layer "B.SilkS")
		)
		(fp_line
			(start 0.67945 0.3048)
			(end 0.67945 -0.305054)
			(stroke
				(width 0.1)
				(type default)
			)
			(layer "B.Fab")
		)
		(fp_line
			(start 0.67945 -0.305054)
			(end 0.12065 -0.305054)
			(stroke
				(width 0.1)
				(type default)
			)
			(layer "B.Fab")
		)
		(fp_line
			(start 0.12065 0.3048)
			(end 0.67945 0.3048)
			(stroke
				(width 0.1)
				(type default)
			)
			(layer "B.Fab")
		)
		(fp_line
			(start 0.12065 0.2794)
			(end 0.12065 0.3048)
			(stroke
				(width 0.1)
				(type default)
			)
			(layer "B.Fab")
		)
		(fp_line
			(start 0.12065 -0.2794)
			(end -0.12065 -0.2794)
			(stroke
				(width 0.1)
				(type default)
			)
			(layer "B.Fab")
		)
		(fp_line
			(start 0.12065 -0.305054)
			(end 0.12065 -0.2794)
			(stroke
				(width 0.1)
				(type default)
			)
			(layer "B.Fab")
		)
		(fp_line
			(start -0.120396 0.3048)
			(end -0.120396 0.2794)
			(stroke
				(width 0.1)
				(type default)
			)
			(layer "B.Fab")
		)
		(fp_line
			(start -0.120396 0.2794)
			(end 0.12065 0.2794)
			(stroke
				(width 0.1)
				(type default)
			)
			(layer "B.Fab")
		)
		(fp_line
			(start -0.12065 -0.2794)
			(end -0.12065 -0.3048)
			(stroke
				(width 0.1)
				(type default)
			)
			(layer "B.Fab")
		)
		(fp_line
			(start -0.12065 -0.3048)
			(end -0.67945 -0.3048)
			(stroke
				(width 0.1)
				(type default)
			)
			(layer "B.Fab")
		)
		(fp_line
			(start -0.67945 0.3048)
			(end -0.120396 0.3048)
			(stroke
				(width 0.1)
				(type default)
			)
			(layer "B.Fab")
		)
		(fp_line
			(start -0.67945 -0.3048)
			(end -0.67945 0.3048)
			(stroke
				(width 0.1)
				(type default)
			)
			(layer "B.Fab")
		)
		(pad "1" smd circle
			(at 0.40005 0)
			(size 0 0)
			(layers "B.Cu" "B.Mask" "B.Paste")
			(net "P3V3_AUX")
		)
		(pad "2" smd circle
			(at -0.40005 0)
			(size 0 0)
			(layers "B.Cu" "B.Mask" "B.Paste")
			(net "GND")
		)
	)
	(footprint ""
		(layer "B.Cu")
		(at 182.83428 -353.573842 90)
		(property "Reference" "PC1199_P1_3"
			(at 0 0 90)
			(layer "B.SilkS")
			(hide yes)
			(effects
				(font
					(size 1.27 1.27)
				)
				(justify mirror)
			)
		)
		(property "Value" ""
			(at 0 0 90)
			(layer "B.Fab")
			(effects
				(font
					(size 1.27 1.27)
				)
				(justify mirror)
			)
		)
		(duplicate_pad_numbers_are_jumpers no)
		(fp_line
			(start 1.524 -0.762)
			(end -1.524 -0.762)
			(stroke
				(width 0.1524)
				(type default)
			)
			(layer "B.SilkS")
		)
		(fp_line
			(start -1.524 -0.762)
			(end -1.524 0.762)
			(stroke
				(width 0.1524)
				(type default)
			)
			(layer "B.SilkS")
		)
		(fp_line
			(start 1.524 0.762)
			(end 1.524 -0.762)
			(stroke
				(width 0.1524)
				(type default)
			)
			(layer "B.SilkS")
		)
		(fp_line
			(start -1.524 0.762)
			(end 1.524 0.762)
			(stroke
				(width 0.1524)
				(type default)
			)
			(layer "B.SilkS")
		)
		(fp_line
			(start 1.1049 -0.724916)
			(end 1.1049 0.724916)
			(stroke
				(width 0.1)
				(type default)
			)
			(layer "B.Fab")
		)
		(fp_line
			(start -1.1049 -0.724916)
			(end 1.1049 -0.724916)
			(stroke
				(width 0.1)
				(type default)
			)
			(layer "B.Fab")
		)
		(fp_line
			(start 1.1049 0.724916)
			(end -1.1049 0.724916)
			(stroke
				(width 0.1)
				(type default)
			)
			(layer "B.Fab")
		)
		(fp_line
			(start -1.1049 0.724916)
			(end -1.1049 -0.724916)
			(stroke
				(width 0.1)
				(type default)
			)
			(layer "B.Fab")
		)
		(pad "1" smd rect
			(at 0.889 0 90)
			(size 1.016 1.27)
			(layers "B.Cu" "B.Mask" "B.Paste")
			(net "SW_P12V_PVCCFA_EHV_FIVRA_CPU1_R")
		)
		(pad "2" smd rect
			(at -0.889 0 90)
			(size 1.016 1.27)
			(layers "B.Cu" "B.Mask" "B.Paste")
			(net "GND")
		)
	)
	(footprint ""
		(layer "B.Cu")
		(at 27.0383 -129.380996 180)
		(property "Reference" "PR260"
			(at 0 0 0)
			(layer "B.SilkS")
			(hide yes)
			(effects
				(font
					(size 1.27 1.27)
				)
				(justify mirror)
			)
		)
		(property "Value" ""
			(at 0 0 0)
			(layer "B.Fab")
			(effects
				(font
					(size 1.27 1.27)
				)
				(justify mirror)
			)
		)
		(duplicate_pad_numbers_are_jumpers no)
		(fp_line
			(start 0.7874 0.4064)
			(end 0.7874 -0.4064)
			(stroke
				(width 0.1524)
				(type default)
			)
			(layer "B.SilkS")
		)
		(fp_line
			(start 0.7874 -0.4064)
			(end -0.7874 -0.4064)
			(stroke
				(width 0.1524)
				(type default)
			)
			(layer "B.SilkS")
		)
		(fp_line
			(start -0.7874 0.4064)
			(end 0.7874 0.4064)
			(stroke
				(width 0.1524)
				(type default)
			)
			(layer "B.SilkS")
		)
		(fp_line
			(start -0.7874 -0.4064)
			(end -0.7874 0.4064)
			(stroke
				(width 0.1524)
				(type default)
			)
			(layer "B.SilkS")
		)
		(fp_line
			(start 0.67945 0.3048)
			(end 0.67945 -0.305054)
			(stroke
				(width 0.1)
				(type default)
			)
			(layer "B.Fab")
		)
		(fp_line
			(start 0.67945 -0.305054)
			(end 0.12065 -0.305054)
			(stroke
				(width 0.1)
				(type default)
			)
			(layer "B.Fab")
		)
		(fp_line
			(start 0.12065 0.3048)
			(end 0.67945 0.3048)
			(stroke
				(width 0.1)
				(type default)
			)
			(layer "B.Fab")
		)
		(fp_line
			(start 0.12065 0.2794)
			(end 0.12065 0.3048)
			(stroke
				(width 0.1)
				(type default)
			)
			(layer "B.Fab")
		)
		(fp_line
			(start 0.12065 -0.2794)
			(end -0.12065 -0.2794)
			(stroke
				(width 0.1)
				(type default)
			)
			(layer "B.Fab")
		)
		(fp_line
			(start 0.12065 -0.305054)
			(end 0.12065 -0.2794)
			(stroke
				(width 0.1)
				(type default)
			)
			(layer "B.Fab")
		)
		(fp_line
			(start -0.120396 0.3048)
			(end -0.120396 0.2794)
			(stroke
				(width 0.1)
				(type default)
			)
			(layer "B.Fab")
		)
		(fp_line
			(start -0.120396 0.2794)
			(end 0.12065 0.2794)
			(stroke
				(width 0.1)
				(type default)
			)
			(layer "B.Fab")
		)
		(fp_line
			(start -0.12065 -0.2794)
			(end -0.12065 -0.3048)
			(stroke
				(width 0.1)
				(type default)
			)
			(layer "B.Fab")
		)
		(fp_line
			(start -0.12065 -0.3048)
			(end -0.67945 -0.3048)
			(stroke
				(width 0.1)
				(type default)
			)
			(layer "B.Fab")
		)
		(fp_line
			(start -0.67945 0.3048)
			(end -0.120396 0.3048)
			(stroke
				(width 0.1)
				(type default)
			)
			(layer "B.Fab")
		)
		(fp_line
			(start -0.67945 -0.3048)
			(end -0.67945 0.3048)
			(stroke
				(width 0.1)
				(type default)
			)
			(layer "B.Fab")
		)
		(pad "1" smd circle
			(at 0.40005 0)
			(size 0 0)
			(layers "B.Cu" "B.Mask" "B.Paste")
			(net "P12V_AUX")
		)
		(pad "2" smd circle
			(at -0.40005 0)
			(size 0 0)
			(layers "B.Cu" "B.Mask" "B.Paste")
			(net "PVCCINFAON_CPU1_CSPIN")
		)
	)
)
